# S9S_MB_2U (Grand Teton) — schematic netlist excerpt (pin names and nets, part order shuffled) for the footprints in the layout excerpt that follows; sources: Cadence DE-HDL packaged netlist, KiCad conversion of 03242023_DA0F0TMBIJ0_F0T_Motherboard_J_brd_V01_OCP.brd

R183  Q_RES  100 1% CHIP  pkg 0402LF  page 124 : A = PWRGD_CPU0_BUF_R ; B = PVNN_TERM_CPU0
C2334  Q_CAP  0.1UF 25V 10% X7R  pkg 0402  page 211 : A = P3V3_9ZXL045_VDDA ; B = GND
C451  Q_CAP  47UF 4V 20% X6S  pkg C0805  page 78 : A = PVCCD_HV_CPU1 ; B = GND

(kicad_pcb
	(version 20260206)
	(generator "pcbnew")
	(generator_version "10.0")
	(general
		(thickness 1.6)
		(legacy_teardrops no)
	)
	(paper "A4")
	(title_block
		(title "03242023_DA0F0TMBIJ0_F0T_Motherboard_J_brd_V01_OCP.brd")
		(comment 1 "Grand Teton / footprints 6011-6013 of 6105")
	)
	(layers
		(0 "F.Cu" signal "TOP")
		(4 "In1.Cu" signal "GND")
		(6 "In2.Cu" signal "IN1")
		(8 "In3.Cu" signal "GND1")
		(10 "In4.Cu" signal "IN2")
		(12 "In5.Cu" signal "GND2")
		(14 "In6.Cu" signal "IN3")
		(16 "In7.Cu" signal "GND3")
		(18 "In8.Cu" signal "VCC")
		(20 "In9.Cu" signal "VCC1")
		(22 "In10.Cu" signal "GND4")
		(24 "In11.Cu" signal "IN4")
		(26 "In12.Cu" signal "GND5")
		(28 "In13.Cu" signal "IN5")
		(30 "In14.Cu" signal "GND6")
		(32 "In15.Cu" signal "IN6")
		(34 "In16.Cu" signal "GND7")
		(2 "B.Cu" signal "BOTTOM")
		(9 "F.Adhes" user "F.Adhesive")
		(11 "B.Adhes" user "B.Adhesive")
		(13 "F.Paste" user "Package Geometry/Pastemask Top")
		(15 "B.Paste" user "Package Geometry/Pastemask Bottom")
		(5 "F.SilkS" user "Ref Des/Silkscreen Top")
		(7 "B.SilkS" user "Ref Des/Silkscreen Bottom")
		(1 "F.Mask" user "Board Geometry/Soldermask Top")
		(3 "B.Mask" user "Board Geometry/Soldermask Bottom")
		(17 "Dwgs.User" user "User.Drawings")
		(19 "Cmts.User" user "User.Comments")
		(21 "Eco1.User" user "User.Eco1")
		(23 "Eco2.User" user "User.Eco2")
		(25 "Edge.Cuts" user "Board Geometry/Outline")
		(27 "Margin" user)
		(31 "F.CrtYd" user "Package Geometry/Place Bound Top")
		(29 "B.CrtYd" user "Package Geometry/Place Bound Bottom")
		(35 "F.Fab" user "Ref Des/Assembly Top")
		(33 "B.Fab" user "Ref Des/Assembly Bottom")
	)
	(footprint ""
		(layer "B.Cu")
		(at 330.280518 -187.67933 90)
		(property "Reference" "R183"
			(at 0 0 90)
			(layer "B.SilkS")
			(hide yes)
			(effects
				(font
					(size 1.27 1.27)
				)
				(justify mirror)
			)
		)
		(property "Value" ""
			(at 0 0 90)
			(layer "B.Fab")
			(effects
				(font
					(size 1.27 1.27)
				)
				(justify mirror)
			)
		)
		(duplicate_pad_numbers_are_jumpers no)
		(fp_line
			(start 0.7874 -0.4064)
			(end -0.7874 -0.4064)
			(stroke
				(width 0.1524)
				(type default)
			)
			(layer "B.SilkS")
		)
		(fp_line
			(start -0.7874 -0.4064)
			(end -0.7874 0.4064)
			(stroke
				(width 0.1524)
				(type default)
			)
			(layer "B.SilkS")
		)
		(fp_line
			(start 0.7874 0.4064)
			(end 0.7874 -0.4064)
			(stroke
				(width 0.1524)
				(type default)
			)
			(layer "B.SilkS")
		)
		(fp_line
			(start -0.7874 0.4064)
			(end 0.7874 0.4064)
			(stroke
				(width 0.1524)
				(type default)
			)
			(layer "B.SilkS")
		)
		(fp_line
			(start 0.67945 -0.305054)
			(end 0.12065 -0.305054)
			(stroke
				(width 0.1)
				(type default)
			)
			(layer "B.Fab")
		)
		(fp_line
			(start 0.12065 -0.305054)
			(end 0.12065 -0.2794)
			(stroke
				(width 0.1)
				(type default)
			)
			(layer "B.Fab")
		)
		(fp_line
			(start -0.12065 -0.3048)
			(end -0.67945 -0.3048)
			(stroke
				(width 0.1)
				(type default)
			)
			(layer "B.Fab")
		)
		(fp_line
			(start -0.67945 -0.3048)
			(end -0.67945 0.3048)
			(stroke
				(width 0.1)
				(type default)
			)
			(layer "B.Fab")
		)
		(fp_line
			(start 0.12065 -0.2794)
			(end -0.12065 -0.2794)
			(stroke
				(width 0.1)
				(type default)
			)
			(layer "B.Fab")
		)
		(fp_line
			(start -0.12065 -0.2794)
			(end -0.12065 -0.3048)
			(stroke
				(width 0.1)
				(type default)
			)
			(layer "B.Fab")
		)
		(fp_line
			(start 0.12065 0.2794)
			(end 0.12065 0.3048)
			(stroke
				(width 0.1)
				(type default)
			)
			(layer "B.Fab")
		)
		(fp_line
			(start -0.120396 0.2794)
			(end 0.12065 0.2794)
			(stroke
				(width 0.1)
				(type default)
			)
			(layer "B.Fab")
		)
		(fp_line
			(start 0.67945 0.3048)
			(end 0.67945 -0.305054)
			(stroke
				(width 0.1)
				(type default)
			)
			(layer "B.Fab")
		)
		(fp_line
			(start 0.12065 0.3048)
			(end 0.67945 0.3048)
			(stroke
				(width 0.1)
				(type default)
			)
			(layer "B.Fab")
		)
		(fp_line
			(start -0.120396 0.3048)
			(end -0.120396 0.2794)
			(stroke
				(width 0.1)
				(type default)
			)
			(layer "B.Fab")
		)
		(fp_line
			(start -0.67945 0.3048)
			(end -0.120396 0.3048)
			(stroke
				(width 0.1)
				(type default)
			)
			(layer "B.Fab")
		)
		(pad "1" smd circle
			(at 0.40005 0 270)
			(size 0 0)
			(layers "B.Cu" "B.Mask" "B.Paste")
			(net "PWRGD_CPU0_BUF_R")
		)
		(pad "2" smd circle
			(at -0.40005 0 270)
			(size 0 0)
			(layers "B.Cu" "B.Mask" "B.Paste")
			(net "PVNN_TERM_CPU0")
		)
	)
	(footprint ""
		(layer "B.Cu")
		(at 112.9284 -411.716728 -90)
		(property "Reference" "C2334"
			(at 0 0 90)
			(layer "B.SilkS")
			(hide yes)
			(effects
				(font
					(size 1.27 1.27)
				)
				(justify mirror)
			)
		)
		(property "Value" ""
			(at 0 0 90)
			(layer "B.Fab")
			(effects
				(font
					(size 1.27 1.27)
				)
				(justify mirror)
			)
		)
		(duplicate_pad_numbers_are_jumpers no)
		(fp_line
			(start -0.7874 0.4064)
			(end 0.7874 0.4064)
			(stroke
				(width 0.1524)
				(type default)
			)
			(layer "B.SilkS")
		)
		(fp_line
			(start 0.7874 0.4064)
			(end 0.7874 -0.4064)
			(stroke
				(width 0.1524)
				(type default)
			)
			(layer "B.SilkS")
		)
		(fp_line
			(start -0.7874 -0.4064)
			(end -0.7874 0.4064)
			(stroke
				(width 0.1524)
				(type default)
			)
			(layer "B.SilkS")
		)
		(fp_line
			(start 0.7874 -0.4064)
			(end -0.7874 -0.4064)
			(stroke
				(width 0.1524)
				(type default)
			)
			(layer "B.SilkS")
		)
		(fp_line
			(start -0.67945 0.3048)
			(end -0.120396 0.3048)
			(stroke
				(width 0.1)
				(type default)
			)
			(layer "B.Fab")
		)
		(fp_line
			(start -0.120396 0.3048)
			(end -0.120396 0.2794)
			(stroke
				(width 0.1)
				(type default)
			)
			(layer "B.Fab")
		)
		(fp_line
			(start 0.12065 0.3048)
			(end 0.67945 0.3048)
			(stroke
				(width 0.1)
				(type default)
			)
			(layer "B.Fab")
		)
		(fp_line
			(start 0.67945 0.3048)
			(end 0.67945 -0.305054)
			(stroke
				(width 0.1)
				(type default)
			)
			(layer "B.Fab")
		)
		(fp_line
			(start -0.120396 0.2794)
			(end 0.12065 0.2794)
			(stroke
				(width 0.1)
				(type default)
			)
			(layer "B.Fab")
		)
		(fp_line
			(start 0.12065 0.2794)
			(end 0.12065 0.3048)
			(stroke
				(width 0.1)
				(type default)
			)
			(layer "B.Fab")
		)
		(fp_line
			(start -0.12065 -0.2794)
			(end -0.12065 -0.3048)
			(stroke
				(width 0.1)
				(type default)
			)
			(layer "B.Fab")
		)
		(fp_line
			(start 0.12065 -0.2794)
			(end -0.12065 -0.2794)
			(stroke
				(width 0.1)
				(type default)
			)
			(layer "B.Fab")
		)
		(fp_line
			(start -0.67945 -0.3048)
			(end -0.67945 0.3048)
			(stroke
				(width 0.1)
				(type default)
			)
			(layer "B.Fab")
		)
		(fp_line
			(start -0.12065 -0.3048)
			(end -0.67945 -0.3048)
			(stroke
				(width 0.1)
				(type default)
			)
			(layer "B.Fab")
		)
		(fp_line
			(start 0.12065 -0.305054)
			(end 0.12065 -0.2794)
			(stroke
				(width 0.1)
				(type default)
			)
			(layer "B.Fab")
		)
		(fp_line
			(start 0.67945 -0.305054)
			(end 0.12065 -0.305054)
			(stroke
				(width 0.1)
				(type default)
			)
			(layer "B.Fab")
		)
		(pad "1" smd circle
			(at 0.40005 0 90)
			(size 0 0)
			(layers "B.Cu" "B.Mask" "B.Paste")
			(net "P3V3_9ZXL045_VDDA")
		)
		(pad "2" smd circle
			(at -0.40005 0 90)
			(size 0 0)
			(layers "B.Cu" "B.Mask" "B.Paste")
			(net "GND")
		)
	)
	(footprint ""
		(layer "B.Cu")
		(at 103.901494 -248.49836 -90)
		(property "Reference" "C451"
			(at 0 0 90)
			(layer "B.SilkS")
			(hide yes)
			(effects
				(font
					(size 1.27 1.27)
				)
				(justify mirror)
			)
		)
		(property "Value" ""
			(at 0 0 90)
			(layer "B.Fab")
			(effects
				(font
					(size 1.27 1.27)
				)
				(justify mirror)
			)
		)
		(duplicate_pad_numbers_are_jumpers no)
		(fp_line
			(start -1.524 0.762)
			(end 1.524 0.762)
			(stroke
				(width 0.1524)
				(type default)
			)
			(layer "B.SilkS")
		)
		(fp_line
			(start 1.524 0.762)
			(end 1.524 -0.762)
			(stroke
				(width 0.1524)
				(type default)
			)
			(layer "B.SilkS")
		)
		(fp_line
			(start -1.524 -0.762)
			(end -1.524 0.762)
			(stroke
				(width 0.1524)
				(type default)
			)
			(layer "B.SilkS")
		)
		(fp_line
			(start 1.524 -0.762)
			(end -1.524 -0.762)
			(stroke
				(width 0.1524)
				(type default)
			)
			(layer "B.SilkS")
		)
		(fp_line
			(start -1.1049 0.724916)
			(end -1.1049 -0.724916)
			(stroke
				(width 0.1)
				(type default)
			)
			(layer "B.Fab")
		)
		(fp_line
			(start 1.1049 0.724916)
			(end -1.1049 0.724916)
			(stroke
				(width 0.1)
				(type default)
			)
			(layer "B.Fab")
		)
		(fp_line
			(start -1.1049 -0.724916)
			(end 1.1049 -0.724916)
			(stroke
				(width 0.1)
				(type default)
			)
			(layer "B.Fab")
		)
		(fp_line
			(start 1.1049 -0.724916)
			(end 1.1049 0.724916)
			(stroke
				(width 0.1)
				(type default)
			)
			(layer "B.Fab")
		)
		(pad "1" smd rect
			(at 0.889 0 270)
			(size 1.016 1.27)
			(layers "B.Cu" "B.Mask" "B.Paste")
			(net "PVCCD_HV_CPU1")
		)
		(pad "2" smd rect
			(at -0.889 0 270)
			(size 1.016 1.27)
			(layers "B.Cu" "B.Mask" "B.Paste")
			(net "GND")
		)
	)
)
